(kicad_pcb
	(version 20260206)
	(generator "pcbnew")
	(generator_version "10.0")
	(general
		(thickness 1.21888)
		(legacy_teardrops no)
	)
	(paper "A4")
	(title_block
		(title "timecard-v9 — TimeCard-DC-V9_EXP.PcbDoc")
		(comment 1 "Time Appliance Project (Time Card) / footprints 401-402 of 402")
	)
	(layers
		(0 "F.Cu" signal "TOP")
		(4 "In1.Cu" signal "SGND")
		(6 "In2.Cu" signal "IN1")
		(8 "In3.Cu" signal "IN2")
		(10 "In4.Cu" signal "SGND1")
		(2 "B.Cu" signal "BOTTOM")
		(9 "F.Adhes" user "F.Adhesive")
		(11 "B.Adhes" user "B.Adhesive")
		(13 "F.Paste" user "Top Paste")
		(15 "B.Paste" user "Bottom Paste")
		(5 "F.SilkS" user "Top Overlay")
		(7 "B.SilkS" user "Bottom Overlay")
		(1 "F.Mask" user "Top Solder")
		(3 "B.Mask" user "Bottom Solder")
		(17 "Dwgs.User" user "User.Drawings")
		(19 "Cmts.User" user "User.Comments")
		(21 "Eco1.User" user "User.Eco1")
		(23 "Eco2.User" user "User.Eco2")
		(25 "Edge.Cuts" user)
		(27 "Margin" user)
		(31 "F.CrtYd" user "Top Courtyard")
		(29 "B.CrtYd" user "Bottom Courtyard")
		(35 "F.Fab" user "Top Component Center")
		(33 "B.Fab" user "Bottom Component Center")
	)
	(footprint "Vault:FP-C1005-050-0_05-IPC_A"
		(layer "B.Cu")
		(at 177.7216 86.7162 180)
		(property "Reference" "C5"
			(at -0.5 1.006655 0)
			(unlocked yes)
			(layer "B.SilkS")
			(effects
				(font
					(size 0.762 0.762)
					(thickness 0.2286)
				)
				(justify left bottom mirror)
			)
		)
		(property "Value" "2.2uF_16V_0402"
			(at 29.5119 -16.624845 0)
			(unlocked yes)
			(layer "B.SilkS")
			(hide yes)
			(effects
				(font
					(size 0.762 0.762)
					(thickness 0.2286)
				)
				(justify left bottom mirror)
			)
		)
		(sheetname "03-POWER")
		(sheetfile "03-POWER.kicad_sch")
		(duplicate_pad_numbers_are_jumpers no)
		(fp_line
			(start 0.83624 0.73624)
			(end -0.83624 0.73624)
			(stroke
				(width 0.2)
				(type solid)
			)
			(layer "B.SilkS")
		)
		(fp_line
			(start 0.83624 -0.73624)
			(end -0.83624 -0.73624)
			(stroke
				(width 0.2)
				(type solid)
			)
			(layer "B.SilkS")
		)
		(fp_line
			(start 1.03624 0.53624)
			(end -1.03624 0.53624)
			(stroke
				(width 0.2)
				(type solid)
			)
			(layer "B.CrtYd")
		)
		(fp_line
			(start 1.03624 -0.53624)
			(end 1.03624 0.53624)
			(stroke
				(width 0.2)
				(type solid)
			)
			(layer "B.CrtYd")
		)
		(fp_line
			(start 1.03624 -0.53624)
			(end -1.03624 -0.53624)
			(stroke
				(width 0.2)
				(type solid)
			)
			(layer "B.CrtYd")
		)
		(fp_line
			(start -1.03624 -0.53624)
			(end -1.03624 0.53624)
			(stroke
				(width 0.2)
				(type solid)
			)
			(layer "B.CrtYd")
		)
		(fp_line
			(start 1.03624 0.53624)
			(end -1.03624 0.53624)
			(stroke
				(width 0.2)
				(type solid)
			)
			(layer "B.Fab")
		)
		(fp_line
			(start 1.03624 -0.53624)
			(end 1.03624 0.53624)
			(stroke
				(width 0.2)
				(type solid)
			)
			(layer "B.Fab")
		)
		(fp_line
			(start 1.03624 -0.53624)
			(end -1.03624 -0.53624)
			(stroke
				(width 0.2)
				(type solid)
			)
			(layer "B.Fab")
		)
		(fp_line
			(start 0.5 0)
			(end -0.5 0)
			(stroke
				(width 0.1)
				(type solid)
			)
			(layer "B.Fab")
		)
		(fp_line
			(start 0 -0.5)
			(end 0 0.5)
			(stroke
				(width 0.1)
				(type solid)
			)
			(layer "B.Fab")
		)
		(fp_line
			(start -1.03624 -0.53624)
			(end -1.03624 0.53624)
			(stroke
				(width 0.2)
				(type solid)
			)
			(layer "B.Fab")
		)
		(fp_text user "${REFERENCE}"
			(at -0.00001 -0.09602 360)
			(unlocked yes)
			(layer "B.Fab")
			(effects
				(font
					(face "Arial")
					(size 0.63 0.63)
					(thickness 0.1)
				)
				(justify left bottom mirror)
			)
		)
		(pad "1" smd rect
			(at -0.46657 0 180)
			(size 0.73933 0.67248)
			(layers "B.Cu" "B.Mask" "B.Paste")
			(net "P3V3_MUN_VCC")
			(solder_mask_margin 0)
			(solder_paste_margin 0)
		)
		(pad "2" smd rect
			(at 0.46658 0 180)
			(size 0.73933 0.67248)
			(layers "B.Cu" "B.Mask" "B.Paste")
			(net "GND")
			(solder_mask_margin 0)
			(solder_paste_margin 0)
		)
	)
	(footprint "Vault:CAPC1608X87X45ML20T05"
		(layer "B.Cu")
		(at 213.9216 141.5162)
		(property "Reference" "C64"
			(at 0.2286 1.273069 180)
			(unlocked yes)
			(layer "B.SilkS")
			(effects
				(font
					(size 0.762 0.762)
					(thickness 0.2286)
				)
				(justify mirror)
			)
		)
		(property "Value" "0.1uF"
			(at 2.069035 -2.630671 180)
			(unlocked yes)
			(layer "B.SilkS")
			(hide yes)
			(effects
				(font
					(size 0.762 0.762)
					(thickness 0.2286)
				)
				(justify mirror)
			)
		)
		(sheetname "05-GPS_IMU_SENSORS")
		(sheetfile "05-GPS_IMU_SENSORS.kicad_sch")
		(duplicate_pad_numbers_are_jumpers no)
		(pad "1" smd rect
			(at -0.7 0 270)
			(size 1.1 1.05)
			(layers "B.Cu" "B.Mask" "B.Paste")
			(net "GND")
		)
		(pad "2" smd rect
			(at 0.7 0 270)
			(size 1.1 1.05)
			(layers "B.Cu" "B.Mask" "B.Paste")
			(net "GNSS2_P5V0")
		)
	)
)
